# T6G (Grand Teton) — schematic netlist excerpt (pin names and nets, part order shuffled) for the footprints in the layout excerpt that follows; sources: Cadence DE-HDL packaged netlist, KiCad conversion of 04192023_DAF0TMB3IC0_F0TG_MB_C_brd_V02_OCP.brd

R481  Q_RES  0 5% CHIP  pkg 0402LF  page 27 : A = CPU0_XTRIG_L4 ; B = CPU0_XTRIG_R1_L4
C6014  Q_CAP  0.1UF 25V 10% X7R  pkg 0402  page 180 : A = USB3_CPU0_BMC_TX_DN ; B = USB3_CPU0_BMC_TX_C2_DN

(kicad_pcb
	(version 20260206)
	(generator "pcbnew")
	(generator_version "10.0")
	(general
		(thickness 1.6)
		(legacy_teardrops no)
	)
	(paper "A4")
	(title_block
		(title "04192023_DAF0TMB3IC0_F0TG_MB_C_brd_V02_OCP.brd")
		(comment 1 "Grand Teton / footprints 2921-2922 of 8354")
	)
	(layers
		(0 "F.Cu" signal "TOP")
		(4 "In1.Cu" signal "GND")
		(6 "In2.Cu" signal "IN1")
		(8 "In3.Cu" signal "GND1")
		(10 "In4.Cu" signal "IN2")
		(12 "In5.Cu" signal "GND2")
		(14 "In6.Cu" signal "IN3")
		(16 "In7.Cu" signal "GND3")
		(18 "In8.Cu" signal "VCC")
		(20 "In9.Cu" signal "VCC1")
		(22 "In10.Cu" signal "GND4")
		(24 "In11.Cu" signal "IN4")
		(26 "In12.Cu" signal "GND5")
		(28 "In13.Cu" signal "IN5")
		(30 "In14.Cu" signal "GND6")
		(32 "In15.Cu" signal "IN6")
		(34 "In16.Cu" signal "GND7")
		(2 "B.Cu" signal "BOTTOM")
		(9 "F.Adhes" user "F.Adhesive")
		(11 "B.Adhes" user "B.Adhesive")
		(13 "F.Paste" user "Package Geometry/Pastemask Top")
		(15 "B.Paste" user "Package Geometry/Pastemask Bottom")
		(5 "F.SilkS" user "Ref Des/Silkscreen Top")
		(7 "B.SilkS" user "Ref Des/Silkscreen Bottom")
		(1 "F.Mask" user "Board Geometry/Soldermask Top")
		(3 "B.Mask" user "Board Geometry/Soldermask Bottom")
		(17 "Dwgs.User" user "User.Drawings")
		(19 "Cmts.User" user "User.Comments")
		(21 "Eco1.User" user "User.Eco1")
		(23 "Eco2.User" user "User.Eco2")
		(25 "Edge.Cuts" user "Board Geometry/Outline")
		(27 "Margin" user)
		(31 "F.CrtYd" user "Package Geometry/Place Bound Top")
		(29 "B.CrtYd" user "Package Geometry/Place Bound Bottom")
		(35 "F.Fab" user "Ref Des/Assembly Top")
		(33 "B.Fab" user "Ref Des/Assembly Bottom")
	)
	(footprint ""
		(layer "F.Cu")
		(at 350.44761 -60.094876 180)
		(property "Reference" "R481"
			(at 0 0 180)
			(layer "F.SilkS")
			(hide yes)
			(effects
				(font
					(size 1.27 1.27)
				)
			)
		)
		(property "Value" ""
			(at 0 0 180)
			(layer "F.Fab")
			(effects
				(font
					(size 1.27 1.27)
				)
			)
		)
		(duplicate_pad_numbers_are_jumpers no)
		(fp_line
			(start 0.7874 0.4064)
			(end -0.7874 0.4064)
			(stroke
				(width 0.1524)
				(type default)
			)
			(layer "F.SilkS")
		)
		(fp_line
			(start 0.7874 -0.4064)
			(end 0.7874 0.4064)
			(stroke
				(width 0.1524)
				(type default)
			)
			(layer "F.SilkS")
		)
		(fp_line
			(start -0.7874 0.4064)
			(end -0.7874 -0.4064)
			(stroke
				(width 0.1524)
				(type default)
			)
			(layer "F.SilkS")
		)
		(fp_line
			(start -0.7874 -0.4064)
			(end 0.7874 -0.4064)
			(stroke
				(width 0.1524)
				(type default)
			)
			(layer "F.SilkS")
		)
		(fp_line
			(start 0.67945 0.3048)
			(end 0.120396 0.3048)
			(stroke
				(width 0.1)
				(type default)
			)
			(layer "F.Fab")
		)
		(fp_line
			(start 0.67945 -0.3048)
			(end 0.67945 0.3048)
			(stroke
				(width 0.1)
				(type default)
			)
			(layer "F.Fab")
		)
		(fp_line
			(start 0.12065 -0.2794)
			(end 0.12065 -0.3048)
			(stroke
				(width 0.1)
				(type default)
			)
			(layer "F.Fab")
		)
		(fp_line
			(start 0.12065 -0.3048)
			(end 0.67945 -0.3048)
			(stroke
				(width 0.1)
				(type default)
			)
			(layer "F.Fab")
		)
		(fp_line
			(start 0.120396 0.3048)
			(end 0.120396 0.2794)
			(stroke
				(width 0.1)
				(type default)
			)
			(layer "F.Fab")
		)
		(fp_line
			(start 0.120396 0.2794)
			(end -0.12065 0.2794)
			(stroke
				(width 0.1)
				(type default)
			)
			(layer "F.Fab")
		)
		(fp_line
			(start -0.12065 0.3048)
			(end -0.67945 0.3048)
			(stroke
				(width 0.1)
				(type default)
			)
			(layer "F.Fab")
		)
		(fp_line
			(start -0.12065 0.2794)
			(end -0.12065 0.3048)
			(stroke
				(width 0.1)
				(type default)
			)
			(layer "F.Fab")
		)
		(fp_line
			(start -0.12065 -0.2794)
			(end 0.12065 -0.2794)
			(stroke
				(width 0.1)
				(type default)
			)
			(layer "F.Fab")
		)
		(fp_line
			(start -0.12065 -0.305054)
			(end -0.12065 -0.2794)
			(stroke
				(width 0.1)
				(type default)
			)
			(layer "F.Fab")
		)
		(fp_line
			(start -0.67945 0.3048)
			(end -0.67945 -0.305054)
			(stroke
				(width 0.1)
				(type default)
			)
			(layer "F.Fab")
		)
		(fp_line
			(start -0.67945 -0.305054)
			(end -0.12065 -0.305054)
			(stroke
				(width 0.1)
				(type default)
			)
			(layer "F.Fab")
		)
		(pad "1" smd circle
			(at -0.40005 0 180)
			(size 0 0)
			(layers "F.Cu" "F.Mask" "F.Paste")
			(net "CPU0_XTRIG_L4")
		)
		(pad "2" smd circle
			(at 0.40005 0 180)
			(size 0 0)
			(layers "F.Cu" "F.Mask" "F.Paste")
			(net "CPU0_XTRIG_R1_L4")
		)
	)
	(footprint ""
		(layer "F.Cu")
		(at 144.36344 -30.78734 -90)
		(property "Reference" "C6014"
			(at 0 0 270)
			(layer "F.SilkS")
			(hide yes)
			(effects
				(font
					(size 1.27 1.27)
				)
			)
		)
		(property "Value" ""
			(at 0 0 270)
			(layer "F.Fab")
			(effects
				(font
					(size 1.27 1.27)
				)
			)
		)
		(duplicate_pad_numbers_are_jumpers no)
		(fp_line
			(start -0.7874 0.4064)
			(end -0.7874 -0.4064)
			(stroke
				(width 0.1524)
				(type default)
			)
			(layer "F.SilkS")
		)
		(fp_line
			(start 0.7874 0.4064)
			(end -0.7874 0.4064)
			(stroke
				(width 0.1524)
				(type default)
			)
			(layer "F.SilkS")
		)
		(fp_line
			(start -0.7874 -0.4064)
			(end 0.7874 -0.4064)
			(stroke
				(width 0.1524)
				(type default)
			)
			(layer "F.SilkS")
		)
		(fp_line
			(start 0.7874 -0.4064)
			(end 0.7874 0.4064)
			(stroke
				(width 0.1524)
				(type default)
			)
			(layer "F.SilkS")
		)
		(fp_line
			(start -0.6858 0.3048)
			(end -0.6858 -0.3048)
			(stroke
				(width 0.1)
				(type default)
			)
			(layer "F.Fab")
		)
		(fp_line
			(start -0.1016 0.3048)
			(end -0.6858 0.3048)
			(stroke
				(width 0.1)
				(type default)
			)
			(layer "F.Fab")
		)
		(fp_line
			(start 0.1016 0.3048)
			(end 0.1016 0.2794)
			(stroke
				(width 0.1)
				(type default)
			)
			(layer "F.Fab")
		)
		(fp_line
			(start 0.6858 0.3048)
			(end 0.1016 0.3048)
			(stroke
				(width 0.1)
				(type default)
			)
			(layer "F.Fab")
		)
		(fp_line
			(start -0.1016 0.2794)
			(end -0.1016 0.3048)
			(stroke
				(width 0.1)
				(type default)
			)
			(layer "F.Fab")
		)
		(fp_line
			(start 0.1016 0.2794)
			(end -0.1016 0.2794)
			(stroke
				(width 0.1)
				(type default)
			)
			(layer "F.Fab")
		)
		(fp_line
			(start -0.1016 -0.2794)
			(end 0.1016 -0.2794)
			(stroke
				(width 0.1)
				(type default)
			)
			(layer "F.Fab")
		)
		(fp_line
			(start 0.1016 -0.2794)
			(end 0.1016 -0.3048)
			(stroke
				(width 0.1)
				(type default)
			)
			(layer "F.Fab")
		)
		(fp_line
			(start -0.6858 -0.3048)
			(end -0.1016 -0.3048)
			(stroke
				(width 0.1)
				(type default)
			)
			(layer "F.Fab")
		)
		(fp_line
			(start -0.1016 -0.3048)
			(end -0.1016 -0.2794)
			(stroke
				(width 0.1)
				(type default)
			)
			(layer "F.Fab")
		)
		(fp_line
			(start 0.1016 -0.3048)
			(end 0.6858 -0.3048)
			(stroke
				(width 0.1)
				(type default)
			)
			(layer "F.Fab")
		)
		(fp_line
			(start 0.6858 -0.3048)
			(end 0.6858 0.3048)
			(stroke
				(width 0.1)
				(type default)
			)
			(layer "F.Fab")
		)
		(pad "1" smd rect
			(at -0.40005 0 90)
			(size 0.4572 0.508)
			(layers "F.Cu" "F.Mask" "F.Paste")
			(net "USB3_CPU0_BMC_TX_DN")
		)
		(pad "2" smd rect
			(at 0.40005 0 90)
			(size 0.4572 0.508)
			(layers "F.Cu" "F.Mask" "F.Paste")
			(net "USB3_CPU0_BMC_TX_C2_DN")
		)
	)
)
